# T6G (Grand Teton) — schematic netlist excerpt (pin names and nets, part order shuffled) for the footprints in the layout excerpt that follows; sources: Cadence DE-HDL packaged netlist, KiCad conversion of 04192023_DAF0TMB3IC0_F0TG_MB_C_brd_V02_OCP.brd

R6720  Q_RES  10K 1% CHIP  pkg 0201LF  page 320 : A = RST_RT_CPU1_P0_PERST_R_N ; B = GND
R6262  Q_RES  0 5% CHIP  pkg 0402LF  page 179 : A = USB_HUB2_TI_VDD_MRP_USB3DN_RXDM1 ; B = P1V2_CPU0_USB2_DVDD12
PR831  Q_RES  47K 0.1% CHIP  pkg 0402LF  page 190 : A = P3V3_AUX_FB ; B = P3V3_AUX

(kicad_pcb
	(version 20260206)
	(generator "pcbnew")
	(generator_version "10.0")
	(general
		(thickness 1.6)
		(legacy_teardrops no)
	)
	(paper "A4")
	(title_block
		(title "04192023_DAF0TMB3IC0_F0TG_MB_C_brd_V02_OCP.brd")
		(comment 1 "Grand Teton / footprints 1209-1211 of 8354")
	)
	(layers
		(0 "F.Cu" signal "TOP")
		(4 "In1.Cu" signal "GND")
		(6 "In2.Cu" signal "IN1")
		(8 "In3.Cu" signal "GND1")
		(10 "In4.Cu" signal "IN2")
		(12 "In5.Cu" signal "GND2")
		(14 "In6.Cu" signal "IN3")
		(16 "In7.Cu" signal "GND3")
		(18 "In8.Cu" signal "VCC")
		(20 "In9.Cu" signal "VCC1")
		(22 "In10.Cu" signal "GND4")
		(24 "In11.Cu" signal "IN4")
		(26 "In12.Cu" signal "GND5")
		(28 "In13.Cu" signal "IN5")
		(30 "In14.Cu" signal "GND6")
		(32 "In15.Cu" signal "IN6")
		(34 "In16.Cu" signal "GND7")
		(2 "B.Cu" signal "BOTTOM")
		(9 "F.Adhes" user "F.Adhesive")
		(11 "B.Adhes" user "B.Adhesive")
		(13 "F.Paste" user "Package Geometry/Pastemask Top")
		(15 "B.Paste" user "Package Geometry/Pastemask Bottom")
		(5 "F.SilkS" user "Ref Des/Silkscreen Top")
		(7 "B.SilkS" user "Ref Des/Silkscreen Bottom")
		(1 "F.Mask" user "Board Geometry/Soldermask Top")
		(3 "B.Mask" user "Board Geometry/Soldermask Bottom")
		(17 "Dwgs.User" user "User.Drawings")
		(19 "Cmts.User" user "User.Comments")
		(21 "Eco1.User" user "User.Eco1")
		(23 "Eco2.User" user "User.Eco2")
		(25 "Edge.Cuts" user "Board Geometry/Outline")
		(27 "Margin" user)
		(31 "F.CrtYd" user "Package Geometry/Place Bound Top")
		(29 "B.CrtYd" user "Package Geometry/Place Bound Bottom")
		(35 "F.Fab" user "Ref Des/Assembly Top")
		(33 "B.Fab" user "Ref Des/Assembly Bottom")
	)
	(footprint ""
		(layer "F.Cu")
		(at 456.440794 -46.264576 -90)
		(property "Reference" "PR831"
			(at 0 0 270)
			(layer "F.SilkS")
			(hide yes)
			(effects
				(font
					(size 1.27 1.27)
				)
			)
		)
		(property "Value" ""
			(at 0 0 270)
			(layer "F.Fab")
			(effects
				(font
					(size 1.27 1.27)
				)
			)
		)
		(duplicate_pad_numbers_are_jumpers no)
		(fp_line
			(start -0.7874 0.4064)
			(end -0.7874 -0.4064)
			(stroke
				(width 0.1524)
				(type default)
			)
			(layer "F.SilkS")
		)
		(fp_line
			(start 0.7874 0.4064)
			(end -0.7874 0.4064)
			(stroke
				(width 0.1524)
				(type default)
			)
			(layer "F.SilkS")
		)
		(fp_line
			(start -0.7874 -0.4064)
			(end 0.7874 -0.4064)
			(stroke
				(width 0.1524)
				(type default)
			)
			(layer "F.SilkS")
		)
		(fp_line
			(start 0.7874 -0.4064)
			(end 0.7874 0.4064)
			(stroke
				(width 0.1524)
				(type default)
			)
			(layer "F.SilkS")
		)
		(fp_line
			(start -0.67945 0.3048)
			(end -0.67945 -0.305054)
			(stroke
				(width 0.1)
				(type default)
			)
			(layer "F.Fab")
		)
		(fp_line
			(start -0.12065 0.3048)
			(end -0.67945 0.3048)
			(stroke
				(width 0.1)
				(type default)
			)
			(layer "F.Fab")
		)
		(fp_line
			(start 0.120396 0.3048)
			(end 0.120396 0.2794)
			(stroke
				(width 0.1)
				(type default)
			)
			(layer "F.Fab")
		)
		(fp_line
			(start 0.67945 0.3048)
			(end 0.120396 0.3048)
			(stroke
				(width 0.1)
				(type default)
			)
			(layer "F.Fab")
		)
		(fp_line
			(start -0.12065 0.2794)
			(end -0.12065 0.3048)
			(stroke
				(width 0.1)
				(type default)
			)
			(layer "F.Fab")
		)
		(fp_line
			(start 0.120396 0.2794)
			(end -0.12065 0.2794)
			(stroke
				(width 0.1)
				(type default)
			)
			(layer "F.Fab")
		)
		(fp_line
			(start -0.12065 -0.2794)
			(end 0.12065 -0.2794)
			(stroke
				(width 0.1)
				(type default)
			)
			(layer "F.Fab")
		)
		(fp_line
			(start 0.12065 -0.2794)
			(end 0.12065 -0.3048)
			(stroke
				(width 0.1)
				(type default)
			)
			(layer "F.Fab")
		)
		(fp_line
			(start 0.12065 -0.3048)
			(end 0.67945 -0.3048)
			(stroke
				(width 0.1)
				(type default)
			)
			(layer "F.Fab")
		)
		(fp_line
			(start 0.67945 -0.3048)
			(end 0.67945 0.3048)
			(stroke
				(width 0.1)
				(type default)
			)
			(layer "F.Fab")
		)
		(fp_line
			(start -0.67945 -0.305054)
			(end -0.12065 -0.305054)
			(stroke
				(width 0.1)
				(type default)
			)
			(layer "F.Fab")
		)
		(fp_line
			(start -0.12065 -0.305054)
			(end -0.12065 -0.2794)
			(stroke
				(width 0.1)
				(type default)
			)
			(layer "F.Fab")
		)
		(pad "1" smd circle
			(at -0.40005 0 270)
			(size 0 0)
			(layers "F.Cu" "F.Mask" "F.Paste")
			(net "P3V3_AUX_FB")
		)
		(pad "2" smd circle
			(at 0.40005 0 270)
			(size 0 0)
			(layers "F.Cu" "F.Mask" "F.Paste")
			(net "P3V3_AUX")
		)
	)
	(footprint ""
		(layer "F.Cu")
		(at 68.16852 -394.3604 -90)
		(property "Reference" "R6720"
			(at 0 0 270)
			(layer "F.SilkS")
			(hide yes)
			(effects
				(font
					(size 1.27 1.27)
				)
			)
		)
		(property "Value" ""
			(at 0 0 270)
			(layer "F.Fab")
			(effects
				(font
					(size 1.27 1.27)
				)
			)
		)
		(duplicate_pad_numbers_are_jumpers no)
		(fp_line
			(start -0.32512 0.175006)
			(end -0.32512 -0.175006)
			(stroke
				(width 0.1)
				(type default)
			)
			(layer "F.Fab")
		)
		(fp_line
			(start 0.32512 0.175006)
			(end -0.32512 0.175006)
			(stroke
				(width 0.1)
				(type default)
			)
			(layer "F.Fab")
		)
		(fp_line
			(start -0.32512 -0.175006)
			(end 0.32512 -0.175006)
			(stroke
				(width 0.1)
				(type default)
			)
			(layer "F.Fab")
		)
		(fp_line
			(start 0.32512 -0.175006)
			(end 0.32512 0.175006)
			(stroke
				(width 0.1)
				(type default)
			)
			(layer "F.Fab")
		)
		(pad "1" smd rect
			(at -0.2667 0 270)
			(size 0.3048 0.381)
			(layers "F.Cu" "F.Mask" "F.Paste")
			(net "RST_RT_CPU1_P0_PERST_R_N")
		)
		(pad "2" smd rect
			(at 0.2667 0 90)
			(size 0.3048 0.381)
			(layers "F.Cu" "F.Mask" "F.Paste")
			(net "GND")
		)
	)
	(footprint ""
		(layer "F.Cu")
		(at 112.438942 -21.7678 -90)
		(property "Reference" "R6262"
			(at 0 0 270)
			(layer "F.SilkS")
			(hide yes)
			(effects
				(font
					(size 1.27 1.27)
				)
			)
		)
		(property "Value" ""
			(at 0 0 270)
			(layer "F.Fab")
			(effects
				(font
					(size 1.27 1.27)
				)
			)
		)
		(duplicate_pad_numbers_are_jumpers no)
		(fp_line
			(start -0.7874 0.4064)
			(end -0.7874 -0.4064)
			(stroke
				(width 0.1524)
				(type default)
			)
			(layer "F.SilkS")
		)
		(fp_line
			(start 0.7874 0.4064)
			(end -0.7874 0.4064)
			(stroke
				(width 0.1524)
				(type default)
			)
			(layer "F.SilkS")
		)
		(fp_line
			(start -0.7874 -0.4064)
			(end 0.7874 -0.4064)
			(stroke
				(width 0.1524)
				(type default)
			)
			(layer "F.SilkS")
		)
		(fp_line
			(start 0.7874 -0.4064)
			(end 0.7874 0.4064)
			(stroke
				(width 0.1524)
				(type default)
			)
			(layer "F.SilkS")
		)
		(fp_line
			(start -0.67945 0.3048)
			(end -0.67945 -0.305054)
			(stroke
				(width 0.1)
				(type default)
			)
			(layer "F.Fab")
		)
		(fp_line
			(start -0.12065 0.3048)
			(end -0.67945 0.3048)
			(stroke
				(width 0.1)
				(type default)
			)
			(layer "F.Fab")
		)
		(fp_line
			(start 0.120396 0.3048)
			(end 0.120396 0.2794)
			(stroke
				(width 0.1)
				(type default)
			)
			(layer "F.Fab")
		)
		(fp_line
			(start 0.67945 0.3048)
			(end 0.120396 0.3048)
			(stroke
				(width 0.1)
				(type default)
			)
			(layer "F.Fab")
		)
		(fp_line
			(start -0.12065 0.2794)
			(end -0.12065 0.3048)
			(stroke
				(width 0.1)
				(type default)
			)
			(layer "F.Fab")
		)
		(fp_line
			(start 0.120396 0.2794)
			(end -0.12065 0.2794)
			(stroke
				(width 0.1)
				(type default)
			)
			(layer "F.Fab")
		)
		(fp_line
			(start -0.12065 -0.2794)
			(end 0.12065 -0.2794)
			(stroke
				(width 0.1)
				(type default)
			)
			(layer "F.Fab")
		)
		(fp_line
			(start 0.12065 -0.2794)
			(end 0.12065 -0.3048)
			(stroke
				(width 0.1)
				(type default)
			)
			(layer "F.Fab")
		)
		(fp_line
			(start 0.12065 -0.3048)
			(end 0.67945 -0.3048)
			(stroke
				(width 0.1)
				(type default)
			)
			(layer "F.Fab")
		)
		(fp_line
			(start 0.67945 -0.3048)
			(end 0.67945 0.3048)
			(stroke
				(width 0.1)
				(type default)
			)
			(layer "F.Fab")
		)
		(fp_line
			(start -0.67945 -0.305054)
			(end -0.12065 -0.305054)
			(stroke
				(width 0.1)
				(type default)
			)
			(layer "F.Fab")
		)
		(fp_line
			(start -0.12065 -0.305054)
			(end -0.12065 -0.2794)
			(stroke
				(width 0.1)
				(type default)
			)
			(layer "F.Fab")
		)
		(pad "1" smd circle
			(at -0.40005 0 270)
			(size 0 0)
			(layers "F.Cu" "F.Mask" "F.Paste")
			(net "USB_HUB2_TI_VDD_MRP_USB3DN_RXDM1")
		)
		(pad "2" smd circle
			(at 0.40005 0 270)
			(size 0 0)
			(layers "F.Cu" "F.Mask" "F.Paste")
			(net "P1V2_CPU0_USB2_DVDD12")
		)
	)
)
